G04*
G04 #@! TF.GenerationSoftware,Altium Limited,Altium Designer,23.7.1 (13)*
G04*
G04 Layer_Color=8388736*
%FSLAX25Y25*%
%MOIN*%
G70*
G04*
G04 #@! TF.SameCoordinates,AF00DCEB-AC48-4C7C-91EA-99F42E284231*
G04*
G04*
G04 #@! TF.FilePolarity,Positive*
G04*
G01*
G75*
M02*
